# BARRELEYE_G2-MB-PVT-X04-HW-BOM-X26_20180122_Final.xls.xlsx — Single-Sole Source Parts List (bom)
| FOXCONN TECHNOLOGY GROUP |  |  |  |  |  |  |  |  |  |  |  |  |  |  |  |  |  |
| BILL OF MATERIAL |  |  |  |  |  |  |  |  |  |  |  |  |  |  |  |  |  |
| REV OF  BOM | X26 | CUSTOMER | RACKSPACE |  | CUSTOMER P/N |  | PWA P/N： | PWA DESCRIPTION |  |  | PRODUCT CODE |  |  | PWA REV | X04 | DATE | 43122 |
| Sourcing (Single or Sole | Critical Commodity (Y or N) | Component Class (1, 2, other) | Customer PSL (Y/N) | Item Number | Foxconn P/N | Customer P/N | Part Description | Mfr. 1 | Mfr Part # 1 | Proposed Mfr. 2 | Proposed Mfr. 2 PN | Qty | RoHS Status | Location | 2nd Source Qual Build: | Customer Comments | ODM Comments |
| Single | Y | ND | Y(5) | 5 | 62120BE00-015-G |  | SP-CAP,100uF,+/-20%,16V,105℃,G,SMD2816,ESR<=12mOhm | MURATA ELEC. NORTH AMERICA | ECASD91C107M012K01 |  |  | 10 | G | CE21,CE22,CE23,CE24,CE25,CE26,CE27,CE28,CE29,CE30 |  |  |  |
| Single |  |  | Y(4) | 45 | 520300500-223-G |  | DIODE,Schottky,BAT54SLT1G,30V,0.2A,G,SOT23-3,SMD | ON SEMICONDUCTOR CORP | BAT54SLT1G |  |  | 7 | G | D9,D10,D11,D12,D13,D16,D18 |  |  |  |
| Single | Y | 1 | Y(3) | 47 | 520306Y00-223-G |  | DIODE,Schottky Rectifier,MBR0530T1G,30V,0.5A,G,SOD123-2,SMD | ON SEMICONDUCTOR CORP | MBR0530T1G |  |  | 2 | G | D15,D17 |  |  |  |
| Single | Y |  | N | 56 | 52180BC00-223-G |  | DIODE,Array-TVS,ESD8004MUTAG,G,UDFN-10,SMD | ON SEMICONDUCTOR CORP | ESD8004MUTAG |  |  | 1 | G | ED1 |  |  |  |
| Single | N | other | Y(3) | 61 | 730200800-101-G |  | Polyswitch,PTC,6V,1.5A,G,SMD1206 | BOURNS INC | MF-NSMF150-2 |  |  | 1 | G | FS1 |  |  |  |
| Single | ND |  | Y(1) | 62 | 730100400-086-G |  | Fuse,Very fast acting,3A,32V,G,SMD0603 | LITTELFUSE FAR EAST PTE LTD | 0467003.NR |  |  | 2 | G | FS2,FS3 |  |  |  |
| Single | N |  | Y(1) | 66 | 730102000-086-G |  | Fuse,Fast acting,24V,10A,G,SMD1206 | LITTELFUSE FAR EAST PTE LTD | 0501010.WR |  |  | 1 | G | FS22 |  |  |  |
| Single | ND |  | Y(1) | 67 | 730108F00-086-G |  | Fuse,Fast acting,500V,30A,G,SMD | LITTELFUSE FAR EAST PTE LTD | 0505030.MXP |  |  | 2 | G | FS27,FS28 |  |  |  |
| Single | N |  | Y(2) | 68 | 730106S00-088-G |  | Fuse,Fast acting,125V,15A,G,SMD2010 | COOPER BUSSMANN, INC. | CB61F15A-TR2 |  |  | 1 | G | FS29 |  |  |  |
| Single | ND |  | N | 74 | 52113AY00-289-G |  | LED,Red,LTL-42NEW8DH184P,5V,20mA,G,DIP-2 | LITE-ON TECHNOLOGY CORPORATION | LTL-42NEW8DH184P |  |  | 2 | G | LED8,LED9 |  |  |  |
| Single | ND |  | N | 75 | 52113B000-289-G |  | LED,Yellow,LTL-42NSV8DH184P,5V,20mA,G,DIP-2 | LITE-ON TECHNOLOGY CORPORATION | LTL-42NSV8DH184P |  |  | 2 | G | LED10,LED14 |  |  |  |
| Single | ND |  | N | 76 | 52113AW00-289-G |  | LED,Green,LTL-42NGY8DH184P,5V,20mA,G,DIP-2 | LITE-ON TECHNOLOGY CORPORATION | LTL-42NGY8DH184P |  |  | 2 | G | LED11,LED12 |  |  |  |
| Single | ND |  | N | 77 | 52113B100-289-G |  | LED,Blue,LTL42TB6NH184P,5V,30mA,G,DIP-2 | LITE-ON TECHNOLOGY CORPORATION | LTL42TB6NH184P |  |  | 1 | G | LED13 |  |  |  |
| Single | N |  | N | 78 | 52110FE00-289-G |  | LED,Red,LTST-C190KRKT,2.4V,30mA,G,SMD0603 | LITE-ON TECHNOLOGY CORPORATION | LTST-C190KRKT |  |  | 3 | G | LED63,LED64,LED65 |  |  |  |
| Single | ND | ND | Y(1) | 80 | 21040HY00-283-G |  | IC,BROADCOM,BCM5719A1KFBG,A1,G,FBGA-256,SMD | BROADCOM SINGAPORE PTE LTD. | BCM5719A1KFBG |  |  | 1 | G | LOM1 |  |  |  |
| Single | ND | ND | N | 84 | 630100U00-016-G |  | IND,68nH@50MHz,+/-20%,50mA,300mOhm,G,SMD0603 | TDK ELECTRONICS EUROPE GMBH | MLF1608D68NMT |  |  | 3 | G | L18,L19,L20 |  |  |  |
| Single | ND | ND | Y(2) | 85 | 720107U00-015-G |  | FB,220 Ohm@100MHz,+/-25%,2A,50mOhm,G,SMD0805 | MURATA ELEC. NORTH AMERICA | BLM21PG221SN1D |  |  | 1 | G | L21 |  |  |  |
| Single | ND |  | ND | 91 | 62111U700-024-G |  | ECAP,68uF,+/-20%,100V,105C,320mOhm,G,SMD12.5*13.5 | PANASONIC INDUSTRIAL CO.,LTD. | EEEFK2A680AQ |  |  | 6 | G | PSUCE1,PBACE1,PAACE1,PSUCE2,PBACE2,PAACE2 |  |  |  |
| Single | N |  | Y(1) | 92 | 62111QQ00-019-G |  | ECAP,82uF,+/-20%,100V,105C,G,SMD12.5*13.5,ESR<=280mOhm | NICHICON CORPORATION | UCZ2A820MNQ1MS |  |  | 8 | G | PBMCE1,PAMCE1,PBFCE2,PBECE2,PAFCE2,PAECE2,PBACE3,PAACE3 |  |  |  |
| Single | ND |  | N | 106 | 52030TQ00-237-G |  | Diode,Schottky,BAS40-06-7-F,40V,200mA,G,SOT-23-3,SMD | DIODES INCORPORATION | BAS40-06-7-F |  |  | 8 | G | PBMD3,PBFD3,PBED3,PBAD3,PAMD3,PAFD3,PAED3,PAAD3 |  |  |  |
| Single | ND |  | N | 109 | 63035R700-57M-G |  | IND,375nH@1MHz,+/-5%,16A,1.15mOhm,SHLD,G,SMD | Eaton Corporation | CTX01-19603-R |  |  | 2 | G | PBAL2,PAAL2 |  |  |  |
| Single | ND | ND | Y(1) | 149 | 32040FG00-183-G |  | IC,Current Sensor,INA193AIDBVR,G,SOT23-5,SMD | TEXAS INSTRUMENTS | INA193AIDBVR |  |  | 8 | G | PBMU2,PBFU2,PBEU2,PBAU2,PAMU2,PAFU2,PAEU2,PAAU2 |  |  |  |
| Single | N |  | N | 150 | 32014E200-53N-G |  | IC,Regulator,PI3753-00-LGIZ,ADJ,10.3A,G,LGA-108,SMD | Vicor Corporation | PI3753-00-LGIZ |  |  | 2 | G | PBAU3,PAAU3 |  |  |  |
| Single | N |  | N | 151 | 880302200-53N-G |  | Converter,input 0V~60V,185W,G,VTM48MP012T130AA0 | Vicor Corporation | VTM48MP012T130AA0 |  |  | 4 | G | PBAU4,PAAU4,PBAU6,PAAU6 |  |  |  |
| Single | N |  | Y(3) | 152 | 32031MS00-183-G |  | IC,Operation Amplifier,OPA2365AIDR,G,SOIC-8,SMD | TEXAS INSTRUMENTS | OPA2365AIDR |  |  | 8 | G | PBMU5,PBFU5,PBEU5,PAMU5,PAFU5,PAEU5,PBAU7,PAAU7 |  |  |  |
| Single | N |  | Y(4) | 160 | 61100YT00-017-G |  | RES,487 Ohm,+/-0.1%,1/16W,G,SMD0402 | KOA SPEER ELECTRONICS, INC. | RN731ETTP4870B25 |  |  | 4 | G | PBFR34,PBER34,PAFR34,PAER34 |  |  |  |
| Single | N |  | N | 168 | 32014CE00-53N-G |  | IC,Regulator,PI3755-02-LGIZ,ADJ,4A,G,LGA-71,SMD | Vicor Corporation | PI3755-02-LGIZ |  |  | 6 | G | PBMU3,PBFU3,PBEU3,PAMU3,PAFU3,PAEU3 |  |  |  |
| Single | N | ND | N | 169 | 880302600-53N-G |  | Converter,input 0V~52V,120W,G,VTM48RP015C076AG0 | Vicor Corporation | VTM48RP015C076AG0 |  |  | 4 | G | PBFU4,PBEU4,PAFU4,PAEU4 |  |  |  |
| Single | N |  | N | 176 | 320244200-230-G |  | IC,PWM Controller,ISL99227FRZ-T,G,QFN-32,SMD | INTERSIL CORPORATION | ISL99227FRZ-T |  |  | 2 | G | PALU1,PBLU3 |  |  |  |
| Single | ND |  | Y(5) | 179 | 61100YW00-017-G |  | RES,316 Ohm,+/-0.1%,1/16W,G,SMD0402 | KOA SPEER ELECTRONICS, INC. | RN731ETTP3160B25 |  |  | 2 | G | PBMR34,PAMR34 |  |  |  |
| Single | N |  | N | 185 | 880302800-53N-G |  | Converter,input 0V~60V,131W,G,VTM48MP010C105AG0 | Vicor Corporation | VTM48MP010C105AG0 |  |  | 2 | G | PBMU4,PAMU4 |  |  |  |
| Single | ND |  | N | 199 | 10128241-112X0LF |  | CONN,PCIE-8X,V/T,Bla,1mm,30u,G,SMD-98 | FCI CONNECTORS HONGKONG LTD. | 10128241-112X0LF |  |  | 2 | G | PCIE1,PCIE5 |  |  |  |
| Single | ND |  | N | 200 | 10128241-113X0LF |  | CONN,PCIE-16X,V/T,Bla,1mm,30u,G,SMD-164 | FCI CONNECTORS HONGKONG LTD. | 10128241-113X0LF |  |  | 3 | G | PCIE2,PCIE3,PCIE4 |  |  |  |
| Single | Y |  | N | 211 | 32012NN00-238-G |  | IC,Regulator,IR3898MTRPBF,6A,1.5MHZ,G,QFN-17,SMD | INTERNATIONAL RECTIFIER | IR3898MTRPBF |  |  | 11 | G | PUAU1,PSIU1,PSAU1,PRAU1,PQAU1,PPAU1,PIAU1,PFAU1,PETU1,PERU1,PEAU1 |  |  |  |
| Single | ND |  | ND | 217 | 32013PD00-238-G |  | IC,Regulator,IR3883MTRPbF,ADJ,3A,G,QFN-16,SMD | INTERNATIONAL RECTIFIER | IR3883MTRPBF |  |  | 9 | G | PSTU1,PSLU1,PSFU1,PSEU1,PSDU1,PQPU1,PFRU1,PEEU1,PEDU1 |  |  |  |
| Single | N | Other | Y(1) | 220 | 62120CM00-024-G |  | SPEA CAP,220uF,+10%~-35%,6.3V,105C,G,SMD2816,ESR<=15mOhm | PANASONIC INDUSTRIAL CO.,LTD. | EEFCX0J221YR |  |  | 14 | G | PSRCE3000,PSRCE3001,PSPCE3003,PIPCE3003,PFPCE3003,PEPCE3003,PSPCE3004,PIPCE3004,PFPCE3004,PEPCE3004,PSPCE3005,PIPCE3005,PFPCE3005,PEPCE3005 |  |  |  |
| Single | ND |  | N | 229 | 32013HH00-238-G |  | IC,Regulator,IR3447MTRPBF,ADJ,25A,G,PQFN-33 | INTERNATIONAL RECTIFIER | IR3447MTRPBF |  |  | 4 | G | PSPU1,PIPU1,PFPU1,PEPU1 |  |  |  |
| Single | N |  | N | 250 | 52030YE00-223-G |  | DIODE,Schottky,MBR5H100MFST1G,100V,5A,G,SO8FL-8,SMD | ON SEMICONDUCTOR CORP | MBR5H100MFST1G |  |  | 1 | G | PHAD2 |  |  |  |
| Single | N |  | N | 254 | 51032D100-237-G |  | MOS N,DMN10H220L-7,100V,1.6A,220m@10V,G,SOT-23-3,SMD | DIODES INCORPORATION | DMN10H220L-7 |  |  | 2 | G | PHAQ5,PHAQ6 |  |  |  |
| Single | ND |  | ND | 255 | 610601801-32D-G |  | RES,0.5mOhm,+/-1%,2W,G,SMD1225 | Thin Film Technology Corporation | CPA1225R0M50FW-T5 |  |  | 1 | G | PHAR1 |  |  |  |
| Single | ND |  | Y(1) | 264 | 32023RR00-183-G |  | IC,Power Controller,LM5066IPMHX/NOPB,G,HTSSOP-28,SMD | TEXAS INSTRUMENTS | LM5066IPMHX/NOPB |  |  | 1 | G | PHAU1 |  |  |  |
| Single | ND |  | Y(1) | 276 | 62012T500-015-G |  | CAP,22uF,+/-20%,X7S,25V,G,SMD1206 | MURATA ELEC. NORTH AMERICA | GRM31CC71E226ME11L |  |  | 12 | G | PSRC4,PSUC5,PSRC5,PSUC6,PSRC6,PSUC7,PSUC8,PSUC9,PSUC10,PSRC3001,PSRC3002,PSRC3005 |  |  |  |
| Single | N |  | N | 277 | 62013BQ00-015-G |  | CAP,3.6nF,+/-10%,X7R,50V,G,SMD0402 | MURATA ELEC. NORTH AMERICA | GRM155R71H362KA01D |  |  | 1 | G | PSRC7 |  |  |  |
| Single | ND |  | N | 285 | 32013FK00-238-G |  | IC,Regulator,IR3846MTRPBF,ADJ,35A,G,PQFN-26,SMD | INTERNATIONAL RECTIFIER | IR3846MTRPBF |  |  | 1 | G | PSRU1 |  |  |  |
| Single | ND | ND | Y(5) | 298 | 61100Y400-017-G |  | RES,169 Ohm,+/-0.1%,1/16W,G,SMD0402 | KOA SPEER ELECTRONICS, INC. | RN731ETTP1690B25 |  |  | 6 | G | R11,R12,R13,R373,R374,R375 |  |  |  |
| Single | ND |  | Y(5) | 325 | 61100H601-017-G |  | RES,2KOhm,+/-0.5%,1/16W,G,SMD0402 | KOA SPEER ELECTRONICS, INC. | RN731ETTP2001D25 |  |  | 1 | G | R751 |  |  |  |
| Single | Y | ND | N | 362 | 41050W700-46Y-G |  | Flash,AT45DB081E-SHNHC-T,1.65~3.6V,8M,SPI,G,SOIC-8,SMD | Adesto Technologies Corporation | AT45DB081E-SHNHC-T |  |  | 1 | G | U_LOM1_ROM1 |  |  |  |
| Single | ND |  | Y(1) | 365 | 320242G00-183-G |  | IC,Power Controller,LM3880MFX-1AA/NOPB,G,SOT-23-6,SMD | TEXAS INSTRUMENTS | LM3880MFX-1AA/NOPB |  |  | 2 | G | U3,U4 |  |  |  |
| Single | ND |  | N | 367 | 310406Q00-031-G |  | IC,Multiplexer,CBTL01023GM,3V~3.6V,G,XQFN-10,SMD | NXP SEMICONDUCTORS | CBTL01023GM |  |  | 1 | G | U12 |  |  |  |
| Single | Y | ND | Y(1) | 368 | 21040M500-283-G |  | IC,BROADCOM,BCM54612EB1KMLG,B1,G,MLP-48,SMD | BROADCOM SINGAPORE PTE LTD. | BCM54612EB1KMLG |  |  | 1 | G | U13 |  |  |  |
| Single | ND |  | N | 369 | 21012NJ00-687-G |  | IC,ASPEED,AST2500A2-GP,A2,G,TFBGA-456,SMD | ASPEED TECHNOLOGY INC | AST2500A2-GP |  |  | 1 | G | U14 |  |  |  |
| Single | N |  | Y(1) | 372 | 310311G00-183-G |  | IC,Switch,TS3L110RGYR,3V~3.6V,G,VQFN-16,SMD | TEXAS INSTRUMENTS | TS3L110RGYR |  |  | 2 | G | U18,U19 |  |  |  |
| Single | ND |  | N | 373 | 410512F00-233-G |  | Flash,MX66L51235FMI-10G,2.7V~3.6V,512M,SPI,G,SOP-16,SMD | MACRONIX INTERNATIONAL CO.,LTD. | MX66L51235FMI-10G |  |  | 3 | G | U20,U21,U24 |  |  |  |
| Single | ND | ND | Y(2) | 378 | 310504D00-031-G |  | IC,Buffer,74LVC2G125DP,1.65~5.5V,G,TSSOP-8,SMD | NXP SEMICONDUCTORS | 74LVC2G125DP |  |  | 1 | G | U31 |  |  |  |
| Single | ND | ND | N | 380 | 32022AL00-223-G |  | IC,Power Controller,NCP380HSNAJAAT1G,G,TSOP-6,SMD | ON SEMICONDUCTOR CORP | NCP380HSNAJAAT1G |  |  | 3 | G | U33,U35,U177 |  |  |  |
| Single | ND |  | N | 381 | 21081AQ00-426-G |  | IC,RENESAS,uPD720201K8-701-BAC-A,G,QFN-68,SMD | RENESAS TECHNOLOGY AMERICA INC | uPD720201K8-701-BAC-A |  |  | 1 | G | U36 |  |  |  |
| Single | ND | ND | N | 382 | 41050J100-233-G |  | Flash,MX25L5121EMC-20G,2.7~3.6V,512K,SPI,G,SOP-8,SMD | MACRONIX INTERNATIONAL CO.,LTD. | MX25L5121EMC-20G |  |  | 1 | G | U37 |  |  |  |
| Single | ND |  | N | 383 | 210826400-183-G |  | IC,TI,TUSB2077APTR,G,LQFP-48,SMD | TEXAS INSTRUMENTS | TUSB2077APTR |  |  | 1 | G | U38 |  |  |  |
| Single | ND |  | N | 384 | 21081N000-348-G |  | IC,MARVELL,88SE9235A1-NAA2C000,A1,G,QFN-76,SMD | MARVELL SEMICONDUCTOR, INC | 88SE9235A1-NAA2C000[VER.A1] |  |  | 1 | G | U45 |  |  |  |
| Single | Y |  | N | 387 | PCF8523TK/1 |  | IC,NXP,PCF8523TK/1,G,HVSON-8,SMD | NXP SEMICONDUCTORS | PCF8523TK/1 |  |  | 1 | G | U60 |  |  |  |
| Single | ND | ND | N | 389 | 21050R500-298-G |  | IC,SILABS,Si5338C-B06799-GMR,G,QFN-24,SMD | Silicon Laboratories Inc. | SI5338C-B06799-GMR |  |  | 1 | G | U62 |  |  |  |
| Single | ND |  | Y(1) | 390 | 21050P100-217-G |  | IC,IDT,9DBL0452BKILFT,G,VFQFPN-32,SMD | INTEGRATED DEVICE TECHNOLOGY | 9DBL0452BKILFT |  |  | 1 | G | U63 |  |  |  |
| Single | ND |  | Y(1) | 394 | 320231500-183-G |  | IC,Voltage Sensor,TPS3897ADRYR,G,SON-6,SMD | TEXAS INSTRUMENTS | TPS3897ADRYR |  |  | 1 | G | U84 |  |  |  |
| Single | ND |  | Y(1) | 395 | 32020LS00-183-G |  | IC,Power Controller,TPS3801K33DCKR,G,SC-70-5,SMD | TEXAS INSTRUMENTS | TPS3801K33DCKR |  |  | 1 | G | U87 |  |  |  |
| Single | ND |  | Y(3) | 397 | 31050J800-031-G |  | IC,Buffer,PCA9516APW,2.3V~3.6V,G,TSSOP-16,SMD | NXP SEMICONDUCTORS | PCA9516APW |  |  | 4 | G | U92,U93,U94,U95 |  |  |  |
| Single | N |  | Y(2) | 398 | 32021R100-252-G |  | IC,Power Controller,PI3USB102ZLEX,G,TQFN-10P,SMD | PERICOM SEMICONDUCTOR CORP | PI3USB102ZLEX |  |  | 2 | G | U96,U108 |  |  |  |
| Single | ND |  | Y(2) | 399 | 31090C800-031-G |  | IC,Transceiver,74AVC4TD245GU,0.8V~3.6V,G,XQFN-16,SMD | NXP SEMICONDUCTORS | 74AVC4TD245GU |  |  | 1 | G | U97 |  |  |  |
| Single | ND | ND | Y(2) | 401 | 210203M00-031-G |  | IC,NXP,PCA9554PW,G,TSSOP-16,SMD | NXP SEMICONDUCTORS | PCA9554PW |  |  | 2 | G | U99,U100 |  |  |  |
| Single | ND |  | N | 405 | 21081WR00-031-G |  | IC,NXP,PCA9541APW/01,G,TSSOP-16,SMD | NXP SEMICONDUCTORS | PCA9541APW/01 |  |  | 1 | G | U116 |  |  |  |
| Single | ND |  | Y(1) | 406 | 311006F00-031-G |  | IC,Translator,PCA9508D,0.9V~5.5V/2.7V~5.5V,G,SO-8,SMD | NXP SEMICONDUCTORS | PCA9508D |  |  | 1 | G | U164 |  |  |  |
| Single | ND |  | N | 407 | 320242H00-226-G |  | IC,Power Controller,LTC2955CDDB-2#TRMPBF,G,DFN-10,SMD | LINEAR TECHNOLOGY CORPORATION | LTC2955CDDB-2#TRMPBF |  |  | 1 | G | U165 |  |  |  |
| Single | ND |  | N | 408 | 32050Q900-031-G |  | IC,LED Driver,PCA9551PW,G,TSSOP-16,SMD | NXP SEMICONDUCTORS | PCA9551PW |  |  | 2 | G | U166,U172 |  |  |  |
| Single | ND |  | Y(1) | 412 | 31010SB00-183-G |  | Logic IC,Gate,ISO1540DR,3V~5.5V,G,SOIC-8,SMD | TEXAS INSTRUMENTS | ISO1540DR |  |  | 1 | G | U175 |  |  |  |
| Single | ND |  | N | 416 | 71012EC00-162-G |  | XTAL,6MHz,+/-30ppm,20pF,G,SMD | EPSON ELECTRONICS AMERICA,INC. | Q22MA4061164200 |  |  | 1 | G | X4 |  |  |  |
| Single | ND |  | N | 417 | 71011UL00-107-G |  | XTAL,25MHz,+/-15ppm,16pF,G,SMD | DAISHINKU CORPORATION/DAISHINKU SINGAPORE PTE LTD/KDS | 1ZHY25000BB0A |  |  | 1 | G | X5 |  |  |  |
| Single | ND |  | N | 421 | 710213J00-16G-G |  | OSC,25MHz,+/-1.5ppm,3.3V,15pF,G,SMD | SiTime Corporation | SIT5000AC-3B-33N0-25.000000T |  |  | 1 | G | Y3 |  |  |  |
| Single | Y |  | N | 423 | 340660600-GRS-G |  | CONN,Header,Battery Holder,Bla,21.3mm,G/F,G,SMD-2 | LOTES CO LTD | AAA-BAT-063-P02_A |  |  | 1 | G | B1 |  |  |  |
| Single | ND | ND | N | 424 | 2T714BY00-086-G |  | Fuse Clips,10.67mm*7.11mm*7.87mm,G,LITTELFUSE,01220088Z | LITTELFUSE FAR EAST PTE LTD | 01220088Z |  |  | 4 | G | CLIP1,CLIP2,CLIP3,CLIP4 |  |  |  |
| Single | N | ND | N | 428 | 340692800-309-G |  | CONN,Header,Socket,2X30,V/T,Bla,0.5mm,G/F,G,SMD-60 | SAMTEC INC. | QSH-030-01-F-D-A-K-TR |  |  | 1 | G | J2 |  |  |  |
| Single | ND | ND | N | 429 | 3406A2A00-309-G |  | CONN,Header,Shrouded,2X4,V/T,1.27mm,15u,G,SMD-8 | SAMTEC INC. | TFM-104-02-L-D-K-TR |  |  | 1 | G | J9 |  |  |  |
| Single | ND |  | N | 431 | 3406AGV00-317-G |  | CONN,Header,WTB,2X8,V/T,Whi,1.25mm,G,SMD-16 | MOLEX INCORPORATED | 5054331671 |  |  | 1 | G | J12 |  |  |  |
| Single | ND |  | N | 432 | 34071AW00-245-G |  | CONN,SATA,V/T,Bla,1.27mm,15u,G,DIP-22 | AMPHENOL SHANGHAI CORP. | G16CE41210W3EU |  |  | 1 | G | J14 |  |  |  |
| Single | ND |  | N | 434 | 34131WS00-G78-G |  | CONN,BTB,Bla,0.8mm,7.87u,G,SMD-120 | FCI CONNECTORS HONGKONG LTD. | 10139781-122402LF |  |  | 1 | G | J16 |  |  |  |
| Single | ND |  | N | 435 | 34131WT00-G78-G |  | CONN,BTB,Bla,0.8mm,7.87u,G,SMD-80 | FCI CONNECTORS HONGKONG LTD. | 10139781-082402LF |  |  | 2 | G | J17,J18 |  |  |  |
| Single | ND | ND | N | 439 | 3406A9H00-309-G |  | CONN,Header,Socket,V/T,Bla,2.54mm,30u,G,SMD-12 | SAMTEC INC. | SSM-106-S-DV-P-TR |  |  | 1 | G | J34 |  |  |  |
| Single | ND |  | N | 441 | 34051FE00-GRS-G |  | CONN,Modular Jack,USBX2_RJ45,R/A,Bla/Blu,2mm,30u,G,DIP-23 | LOTES CO LTD | AUSBS002-K001C05 |  |  | 1 | G | J99 |  |  |  |
| Single | ND |  | N | 443 | 340653G00-317-G |  | CONN,Header,Shrouded,2X11,V/T,Bla,2mm,30u,G,SMD-22 | MOLEX INCORPORATED | 87832-6023 |  |  | 1 | G | J102 |  |  |  |
| Single | ND |  | N | 444 | 3406ALY00-317-G |  | CONN,Header,Shrouded,2X6,V/T,Bla,2mm,30u,G,SMD-12 | MOLEX INCORPORATED | 87832-5523 |  |  | 1 | G | J103 |  |  |  |
| Single | N |  | N | 448 | ISL68137IRAZ-GG05 |  | IC,PWM Controller,ISL68137IRAZ-T,G,QFN-48,SMD | INTERSIL CORPORATION | ISL68137IRAZ-GG05 |  |  | 8 | G | PBMU1,PBFU1,PBEU1,PBAU1,PAMU1,PAFU1,PAEU1,PAAU1 |  |  |  |
| Single | N |  | N | 449 | IR38064MTRP=GZS |  | IC,Regulator,IR38064MTRP=GZS ,ADJ,35A,G,QFN-26,SMD | INTERNATIONAL RECTIFIER | IR38064MTRP=GZS |  |  | 2 | G | PBNU1,PANU1 |  |  |  |
| Single | ND |  | N | 451 | 34081GH00-653-G |  | CONN,Switch,tact,Brown,50mA,12V,G,DIP-4 | DIPTRONICS MANUFACTURING INC. | DTSA-644N-Q |  |  | 2 | G | SW3,SW4 |  |  |  |
| Single |  |  |  | 452 | 340109B00-600-G |  | POWER9 CPU Socket for LGA3899-HYBRID | FOXCONN TECHNOLOGY CO.,LTD. | PE38993-51BC1-1H |  |  | 2 | G | U1,U10 |  |  |  |
| Single | ND |  | Y(1) | 453 | UCD90160RGCR-C13 |  | IC,Power Controller,UCD90160RGCR,G,VQFN-64,SMD | TEXAS INSTRUMENTS | UCD90160RGCR-C13 |  |  | 1 | G | U5 |  |  |  |
| Single | ND | ND | N | 454 | 34061E400-GRS-G |  | CONN,Socket,SPI Flash,V/T,Bla,1.27mm,G/F,G,SMD-16 | LOTES CO LTD | ACA-SPI-006-F01 |  |  | 2 | G | U22,U23 |  |  |  |
